# T6G (Grand Teton) — schematic netlist excerpt (pin names and nets, part order shuffled) for the footprints in the layout excerpt that follows; sources: Cadence DE-HDL packaged netlist, KiCad conversion of 04192023_DAF0TMB3IC0_F0TG_MB_C_brd_V02_OCP.brd

J29  SCONN288_DDR506112002KQ  IO  pkg DDR288S_1-1VXC  page 107
  VIN_BULK0  = P12V_MEM_CPU1
  RFU0  = NC
  VIN_MGMT  = P3V3_AUX
  HSCL  = I3C_SPD_DDRJ_CPU1_SCL
  HSDA  = I3C_SPD_DDRJ_CPU1_SDA
  VSS0  = GND
  DQ0_A  = M_J_CPU1_SA_DQ<0>
  VSS1  = GND
  DQ1_A  = M_J_CPU1_SA_DQ<1>
  VSS2  = GND
  DQS0_A_T  = M_J_CPU1_SA_DQS_DP<0>
  DQS0_A_C  = M_J_CPU1_SA_DQS_DN<0>
  VSS3  = GND
  DQ4_A  = M_J_CPU1_SA_DQ<4>
  VSS4  = GND
  DQ5_A  = M_J_CPU1_SA_DQ<5>
  VSS5  = GND
  DQ8_A  = M_J_CPU1_SA_DQ<8>
  VSS6  = GND
  DQ9_A  = M_J_CPU1_SA_DQ<9>
  VSS7  = GND
  DQS1_A_T  = M_J_CPU1_SA_DQS_DP<1>
  DQS1_A_C  = M_J_CPU1_SA_DQS_DN<1>
  VSS8  = GND
  DQ12_A  = M_J_CPU1_SA_DQ<12>
  VSS9  = GND
  DQ13_A  = M_J_CPU1_SA_DQ<13>
  VSS10  = GND
  DQ16_A  = M_J_CPU1_SA_DQ<16>
  VSS11  = GND
  DQ17_A  = M_J_CPU1_SA_DQ<17>
  VSS12  = GND
  DQS2_A_T  = M_J_CPU1_SA_DQS_DP<2>
  DQS2_A_C  = M_J_CPU1_SA_DQS_DN<2>
  VSS13  = GND
  DQ20_A  = M_J_CPU1_SA_DQ<20>
  VSS14  = GND
  DQ21_A  = M_J_CPU1_SA_DQ<21>
  VSS15  = GND
  DQ24_A  = M_J_CPU1_SA_DQ<24>
  VSS16  = GND
  DQ25_A  = M_J_CPU1_SA_DQ<25>
  VSS17  = GND
  DQS3_A_T  = M_J_CPU1_SA_DQS_DP<3>
  DQS3_A_C  = M_J_CPU1_SA_DQS_DN<3>
  VSS18  = GND
  DQ28_A  = M_J_CPU1_SA_DQ<28>
  VSS19  = GND
  DQ29_A  = M_J_CPU1_SA_DQ<29>
  VSS20  = GND
  CB0_A  = M_J_CPU1_SA_CB<0>
  VSS21  = GND
  CB1_A  = M_J_CPU1_SA_CB<1>
  VSS22  = GND
  DQS4_A_T  = M_J_CPU1_SA_DQS_DP<4>
  DQS4_A_C  = M_J_CPU1_SA_DQS_DN<4>
  VSS23  = GND
  CB4_A  = M_J_CPU1_SA_CB<4>
  VSS24  = GND
  CB5_A  = M_J_CPU1_SA_CB<5>
  VSS25  = GND
  ALERT_N  = M_J_CPU1_ALERT_N
  VSS26  = GND
  CS0_A_N  = M_J_CPU1_SA_CS_N<0>
  VSS27  = GND
  CA0_A  = M_J_CPU1_SA_CA<0>
  VSS28  = GND
  CA2_A  = M_J_CPU1_SA_CA<2>
  VSS29  = GND
  CA4_A  = M_J_CPU1_SA_CA<4>
  VSS30  = GND
  CA6_A  = M_J_CPU1_SA_CA<6>
  VSS31  = GND
  PAR_A  = M_J_CPU1_SA_PAR
  VSS32  = GND
  CA0_B  = M_J_CPU1_SB_CA<0>
  VSS33  = GND
  CA2_B  = M_J_CPU1_SB_CA<2>
  VSS34  = GND
  CA4_B  = M_J_CPU1_SB_CA<4>
  VSS35  = GND
  CA6_B  = M_J_CPU1_SB_CA<6>
  VSS36  = GND
  CS0_B_N  = M_J_CPU1_SB_CS_N<0>
  VSS37  = GND
  \lbd||rsp_a_n\  = M_J_CPU1_SA_RSP<0>
  \lbs||rsp_b_n\  = M_J_CPU1_SB_RSP<0>
  VSS38  = GND
  CB4_B  = M_J_CPU1_SB_CB<4>
  VSS39  = GND
  CB5_B  = M_J_CPU1_SB_CB<5>
  VSS40  = GND
  \dqs9_b_t||tdqs9_b_t||dbi4_b_n\  = M_J_CPU1_SB_DQS_DP<9>
  \dqs9_b_c||tdqs9_b_c\  = M_J_CPU1_SB_DQS_DN<9>
  VSS41  = GND
  CB0_B  = M_J_CPU1_SB_CB<0>
  VSS42  = GND
  CB1_B  = M_J_CPU1_SB_CB<1>
  VSS43  = GND
  DQ0_B  = M_J_CPU1_SB_DQ<0>
  VSS44  = GND
  DQ1_B  = M_J_CPU1_SB_DQ<1>
  VSS45  = GND
  DQS0_B_T  = M_J_CPU1_SB_DQS_DP<0>
  DQS0_B_C  = M_J_CPU1_SB_DQS_DN<0>
  VSS46  = GND
  DQ4_B  = M_J_CPU1_SB_DQ<4>
  VSS47  = GND
  DQ5_B  = M_J_CPU1_SB_DQ<5>
  VSS48  = GND
  DQ8_B  = M_J_CPU1_SB_DQ<8>
  VSS49  = GND
  DQ9_B  = M_J_CPU1_SB_DQ<9>
  VSS50  = GND
  DQS1_B_T  = M_J_CPU1_SB_DQS_DP<1>
  DQS1_B_C  = M_J_CPU1_SB_DQS_DN<1>
  VSS51  = GND
  DQ12_B  = M_J_CPU1_SB_DQ<12>
  VSS52  = GND
  DQ13_B  = M_J_CPU1_SB_DQ<13>
  VSS53  = GND
  DQ16_B  = M_J_CPU1_SB_DQ<16>
  VSS54  = GND
  DQ17_B  = M_J_CPU1_SB_DQ<17>
  VSS55  = GND
  DQS2_B_T  = M_J_CPU1_SB_DQS_DP<2>
  DQS2_B_C  = M_J_CPU1_SB_DQS_DN<2>
  VSS56  = GND
  DQ20_B  = M_J_CPU1_SB_DQ<20>
  VSS57  = GND
  DQ21_B  = M_J_CPU1_SB_DQ<21>
  VSS58  = GND
  DQ24_B  = M_J_CPU1_SB_DQ<24>
  VSS59  = GND
  DQ25_B  = M_J_CPU1_SB_DQ<25>
  VSS60  = GND
  DQS3_B_T  = M_J_CPU1_SB_DQS_DP<3>
  DQS3_B_C  = M_J_CPU1_SB_DQS_DN<3>
  VSS61  = GND
  DQ28_B  = M_J_CPU1_SB_DQ<28>
  VSS62  = GND
  DQ29_B  = M_J_CPU1_SB_DQ<29>
  VSS63  = GND
  RFU1  = NC
  VIN_BULK1  = P12V_MEM_CPU1
  VIN_BULK2  = P12V_MEM_CPU1
  \pwr_good||fail_n\  = PWRGD_CHJ_CPU1_DIMM
  HAS  = PD_CHJ_CPU1_DIMM_SAA
  RFU2  = NC
  RFU3  = NC
  VSS64  = GND
  DQ2_A  = M_J_CPU1_SA_DQ<2>
  VSS65  = GND
  DQ3_A  = M_J_CPU1_SA_DQ<3>
  VSS66  = GND
  \dqs5_a_c||tdqs5_a_c||dqs5_a_t||tdqs5_a_t\  = M_J_CPU1_SA_DQS_DN<5>
  \dqs5_a_t||tdqs5_a_t\  = M_J_CPU1_SA_DQS_DP<5>
  VSS67  = GND
  DQ6_A  = M_J_CPU1_SA_DQ<6>
  VSS68  = GND
  DQ7_A  = M_J_CPU1_SA_DQ<7>
  VSS69  = GND
  DQ10_A  = M_J_CPU1_SA_DQ<10>
  VSS70  = GND
  DQ11_A  = M_J_CPU1_SA_DQ<11>
  VSS71  = GND
  \dqs6_a_c||tdqs6_a_c||dqs6_a_t||tdqs6_a_t\  = M_J_CPU1_SA_DQS_DN<6>
  \dqs6_a_t||tdqs6_a_t\  = M_J_CPU1_SA_DQS_DP<6>
  VSS72  = GND
  DQ14_A  = M_J_CPU1_SA_DQ<14>
  VSS73  = GND
  DQ15_A  = M_J_CPU1_SA_DQ<15>
  VSS74  = GND
  DQ18_A  = M_J_CPU1_SA_DQ<18>
  VSS75  = GND
  DQ19_A  = M_J_CPU1_SA_DQ<19>
  VSS76  = GND
  \dqs7_a_c||tdqs7_a_c\  = M_J_CPU1_SA_DQS_DN<7>
  \dqs7_a_t||tdqs7_a_t\  = M_J_CPU1_SA_DQS_DP<7>
  VSS77  = GND
  DQ22_A  = M_J_CPU1_SA_DQ<22>
  VSS78  = GND
  DQ23_A  = M_J_CPU1_SA_DQ<23>
  VSS79  = GND
  DQ26_A  = M_J_CPU1_SA_DQ<26>
  VSS80  = GND
  DQ27_A  = M_J_CPU1_SA_DQ<27>
  VSS81  = GND
  \dqs8_a_c||tdqs8_a_c\  = M_J_CPU1_SA_DQS_DN<8>
  \dqs8_a_t||tdqs8_a_t\  = M_J_CPU1_SA_DQS_DP<8>
  VSS82  = GND
  DQ30_A  = M_J_CPU1_SA_DQ<30>
  VSS83  = GND
  DQ31_A  = M_J_CPU1_SA_DQ<31>
  VSS84  = GND
  CB2_A  = M_J_CPU1_SA_CB<2>
  VSS85  = GND
  CB3_A  = M_J_CPU1_SA_CB<3>
  VSS86  = GND
  \dqs9_a_c||tdqs9_a_c\  = M_J_CPU1_SA_DQS_DN<9>
  \dqs9_a_t||tdqs9_a_t\  = M_J_CPU1_SA_DQS_DP<9>
  VSS87  = GND
  CB6_A  = M_J_CPU1_SA_CB<6>
  VSS88  = GND
  CB7_A  = M_J_CPU1_SA_CB<7>
  VSS89  = GND
  RESET_N  = M_J_CPU1_RESET_N
  VSS90  = GND
  CS1_A_N  = M_J_CPU1_SA_CS_N<1>
  VSS91  = GND
  CA1_A  = M_J_CPU1_SA_CA<1>
  VSS92  = GND
  CA3_A  = M_J_CPU1_SA_CA<3>
  VSS93  = GND
  CA5_A  = M_J_CPU1_SA_CA<5>
  VSS94  = GND
  CK_T  = M_J_CPU1_CLK_DP<0>
  CK_C  = M_J_CPU1_CLK_DN<0>
  VSS95  = GND
  RFU4  = NC
  CA1_B  = M_J_CPU1_SB_CA<1>
  VSS96  = GND
  CA3_B  = M_J_CPU1_SB_CA<3>
  VSS97  = GND
  CA5_B  = M_J_CPU1_SB_CA<5>
  VSS98  = GND
  PAR_B  = M_J_CPU1_SB_PAR
  VSS99  = GND
  CS1_B_N  = M_J_CPU1_SB_CS_N<1>
  VSS100  = GND
  RFU5  = NC
  RFU6  = NC
  VSS101  = GND
  CB6_B  = M_J_CPU1_SB_CB<6>
  VSS102  = GND
  CB7_B  = M_J_CPU1_SB_CB<7>
  VSS103  = GND
  DQS4_B_C  = M_J_CPU1_SB_DQS_DN<4>
  DQS4_B_T  = M_J_CPU1_SB_DQS_DP<4>
  VSS104  = GND
  CB2_B  = M_J_CPU1_SB_CB<2>
  VSS105  = GND
  CB3_B  = M_J_CPU1_SB_CB<3>
  VSS106  = GND
  DQ2_B  = M_J_CPU1_SB_DQ<2>
  VSS107  = GND
  DQ3_B  = M_J_CPU1_SB_DQ<3>
  VSS108  = GND
  \dqs5_b_c||tdqs5_b_c\  = M_J_CPU1_SB_DQS_DN<5>
  \dqs5_b_t||tdqs5_b_t\  = M_J_CPU1_SB_DQS_DP<5>
  VSS109  = GND
  DQ6_B  = M_J_CPU1_SB_DQ<6>
  VSS110  = GND
  DQ7_B  = M_J_CPU1_SB_DQ<7>
  VSS111  = GND
  DQ10_B  = M_J_CPU1_SB_DQ<10>
  VSS112  = GND
  DQ11_B  = M_J_CPU1_SB_DQ<11>
  VSS113  = GND
  \dqs6_b_c||tdqs6_b_c\  = M_J_CPU1_SB_DQS_DN<6>
  \dqs6_b_t||tdqs6_b_t\  = M_J_CPU1_SB_DQS_DP<6>
  VSS114  = GND
  DQ14_B  = M_J_CPU1_SB_DQ<14>
  VSS115  = GND
  DQ15_B  = M_J_CPU1_SB_DQ<15>
  VSS116  = GND
  DQ18_B  = M_J_CPU1_SB_DQ<18>
  VSS117  = GND
  DQ19_B  = M_J_CPU1_SB_DQ<19>
  VSS118  = GND
  \dqs7_b_c||tdqs7_b_c\  = M_J_CPU1_SB_DQS_DN<7>
  \dqs7_b_t||tdqs7_b_t\  = M_J_CPU1_SB_DQS_DP<7>
  VSS119  = GND
  DQ22_B  = M_J_CPU1_SB_DQ<22>
  VSS120  = GND
  DQ23_B  = M_J_CPU1_SB_DQ<23>
  VSS121  = GND
  DQ26_B  = M_J_CPU1_SB_DQ<26>
  VSS122  = GND
  DQ27_B  = M_J_CPU1_SB_DQ<27>
  VSS123  = GND
  \dqs8_b_c||tdqs8_b_c\  = M_J_CPU1_SB_DQS_DN<8>
  \dqs8_b_t||tdqs8_b_t\  = M_J_CPU1_SB_DQS_DP<8>
  VSS124  = GND
  DQ30_B  = M_J_CPU1_SB_DQ<30>
  VSS125  = GND
  DQ31_B  = M_J_CPU1_SB_DQ<31>
  VSS126  = GND
  G1  = GND
  G2  = GND
  G3  = GND

(kicad_pcb
	(version 20260206)
	(generator "pcbnew")
	(generator_version "10.0")
	(general
		(thickness 1.6)
		(legacy_teardrops no)
	)
	(paper "A4")
	(title_block
		(title "04192023_DAF0TMB3IC0_F0TG_MB_C_brd_V02_OCP.brd")
		(comment 1 "Grand Teton / footprint 1456 of 8354 (J29), pads 46-91 of 291")
	)
	(layers
		(0 "F.Cu" signal "TOP")
		(4 "In1.Cu" signal "GND")
		(6 "In2.Cu" signal "IN1")
		(8 "In3.Cu" signal "GND1")
		(10 "In4.Cu" signal "IN2")
		(12 "In5.Cu" signal "GND2")
		(14 "In6.Cu" signal "IN3")
		(16 "In7.Cu" signal "GND3")
		(18 "In8.Cu" signal "VCC")
		(20 "In9.Cu" signal "VCC1")
		(22 "In10.Cu" signal "GND4")
		(24 "In11.Cu" signal "IN4")
		(26 "In12.Cu" signal "GND5")
		(28 "In13.Cu" signal "IN5")
		(30 "In14.Cu" signal "GND6")
		(32 "In15.Cu" signal "IN6")
		(34 "In16.Cu" signal "GND7")
		(2 "B.Cu" signal "BOTTOM")
		(9 "F.Adhes" user "F.Adhesive")
		(11 "B.Adhes" user "B.Adhesive")
		(13 "F.Paste" user "Package Geometry/Pastemask Top")
		(15 "B.Paste" user "Package Geometry/Pastemask Bottom")
		(5 "F.SilkS" user "Ref Des/Silkscreen Top")
		(7 "B.SilkS" user "Ref Des/Silkscreen Bottom")
		(1 "F.Mask" user "Board Geometry/Soldermask Top")
		(3 "B.Mask" user "Board Geometry/Soldermask Bottom")
		(17 "Dwgs.User" user "User.Drawings")
		(19 "Cmts.User" user "User.Comments")
		(21 "Eco1.User" user "User.Eco1")
		(23 "Eco2.User" user "User.Eco2")
		(25 "Edge.Cuts" user "Board Geometry/Outline")
		(27 "Margin" user)
		(31 "F.CrtYd" user "Package Geometry/Place Bound Top")
		(29 "B.CrtYd" user "Package Geometry/Place Bound Bottom")
		(35 "F.Fab" user "Ref Des/Assembly Top")
		(33 "B.Fab" user "Ref Des/Assembly Bottom")
	)
	(footprint ""
		(layer "F.Cu")
		(at 189.110112 -255.560322 180)
		(property "Reference" "J29"
			(at -2.7178 -81.857088 0)
			(unlocked yes)
			(layer "F.SilkS")
			(effects
				(font
					(size 0.7874 0.5842)
					(thickness 0.1524)
				)
			)
		)
		(property "Value" ""
			(at 0 0 180)
			(layer "F.Fab")
			(effects
				(font
					(size 1.27 1.27)
				)
			)
		)
		(duplicate_pad_numbers_are_jumpers no)
		(pad "46" smd rect
			(at -2.050034 -25.07488 90)
			(size 0.519938 1.4986)
			(layers "F.Cu" "F.Mask" "F.Paste")
			(net "GND")
		)
		(pad "47" smd rect
			(at -2.050034 -24.224996 90)
			(size 0.519938 1.4986)
			(layers "F.Cu" "F.Mask" "F.Paste")
			(net "M_J_CPU1_SA_DQ<28>")
		)
		(pad "48" smd rect
			(at -2.050034 -23.375112 90)
			(size 0.519938 1.4986)
			(layers "F.Cu" "F.Mask" "F.Paste")
			(net "GND")
		)
		(pad "49" smd rect
			(at -2.050034 -22.524974 90)
			(size 0.519938 1.4986)
			(layers "F.Cu" "F.Mask" "F.Paste")
			(net "M_J_CPU1_SA_DQ<29>")
		)
		(pad "50" smd rect
			(at -2.050034 -21.67509 90)
			(size 0.519938 1.4986)
			(layers "F.Cu" "F.Mask" "F.Paste")
			(net "GND")
		)
		(pad "51" smd rect
			(at -2.050034 -20.824952 90)
			(size 0.519938 1.4986)
			(layers "F.Cu" "F.Mask" "F.Paste")
			(net "M_J_CPU1_SA_CB<0>")
		)
		(pad "52" smd rect
			(at -2.050034 -19.975068 90)
			(size 0.519938 1.4986)
			(layers "F.Cu" "F.Mask" "F.Paste")
			(net "GND")
		)
		(pad "53" smd rect
			(at -2.050034 -19.12493 90)
			(size 0.519938 1.4986)
			(layers "F.Cu" "F.Mask" "F.Paste")
			(net "M_J_CPU1_SA_CB<1>")
		)
		(pad "54" smd rect
			(at -2.050034 -18.275046 90)
			(size 0.519938 1.4986)
			(layers "F.Cu" "F.Mask" "F.Paste")
			(net "GND")
		)
		(pad "55" smd rect
			(at -2.050034 -17.424908 90)
			(size 0.519938 1.4986)
			(layers "F.Cu" "F.Mask" "F.Paste")
			(net "M_J_CPU1_SA_DQS_DP<4>")
		)
		(pad "56" smd rect
			(at -2.050034 -16.575024 90)
			(size 0.519938 1.4986)
			(layers "F.Cu" "F.Mask" "F.Paste")
			(net "M_J_CPU1_SA_DQS_DN<4>")
		)
		(pad "57" smd rect
			(at -2.050034 -15.724886 90)
			(size 0.519938 1.4986)
			(layers "F.Cu" "F.Mask" "F.Paste")
			(net "GND")
		)
		(pad "58" smd rect
			(at -2.050034 -14.875002 90)
			(size 0.519938 1.4986)
			(layers "F.Cu" "F.Mask" "F.Paste")
			(net "M_J_CPU1_SA_CB<4>")
		)
		(pad "59" smd rect
			(at -2.050034 -14.025118 90)
			(size 0.519938 1.4986)
			(layers "F.Cu" "F.Mask" "F.Paste")
			(net "GND")
		)
		(pad "60" smd rect
			(at -2.050034 -13.17498 90)
			(size 0.519938 1.4986)
			(layers "F.Cu" "F.Mask" "F.Paste")
			(net "M_J_CPU1_SA_CB<5>")
		)
		(pad "61" smd rect
			(at -2.050034 -12.325096 90)
			(size 0.519938 1.4986)
			(layers "F.Cu" "F.Mask" "F.Paste")
			(net "GND")
		)
		(pad "62" smd rect
			(at -2.050034 -11.474958 90)
			(size 0.519938 1.4986)
			(layers "F.Cu" "F.Mask" "F.Paste")
			(net "M_J_CPU1_ALERT_N")
		)
		(pad "63" smd rect
			(at -2.050034 -10.625074 90)
			(size 0.519938 1.4986)
			(layers "F.Cu" "F.Mask" "F.Paste")
			(net "GND")
		)
		(pad "64" smd rect
			(at -2.050034 -9.774936 90)
			(size 0.519938 1.4986)
			(layers "F.Cu" "F.Mask" "F.Paste")
			(net "M_J_CPU1_SA_CS_N<0>")
		)
		(pad "65" smd rect
			(at -2.050034 -8.925052 90)
			(size 0.519938 1.4986)
			(layers "F.Cu" "F.Mask" "F.Paste")
			(net "GND")
		)
		(pad "66" smd rect
			(at -2.050034 -8.074914 90)
			(size 0.519938 1.4986)
			(layers "F.Cu" "F.Mask" "F.Paste")
			(net "M_J_CPU1_SA_CA<0>")
		)
		(pad "67" smd rect
			(at -2.050034 -7.22503 90)
			(size 0.519938 1.4986)
			(layers "F.Cu" "F.Mask" "F.Paste")
			(net "GND")
		)
		(pad "68" smd rect
			(at -2.050034 -6.374892 90)
			(size 0.519938 1.4986)
			(layers "F.Cu" "F.Mask" "F.Paste")
			(net "M_J_CPU1_SA_CA<2>")
		)
		(pad "69" smd rect
			(at -2.050034 -5.525008 90)
			(size 0.519938 1.4986)
			(layers "F.Cu" "F.Mask" "F.Paste")
			(net "GND")
		)
		(pad "70" smd rect
			(at -2.050034 -4.675124 90)
			(size 0.519938 1.4986)
			(layers "F.Cu" "F.Mask" "F.Paste")
			(net "M_J_CPU1_SA_CA<4>")
		)
		(pad "71" smd rect
			(at -2.050034 -3.824986 90)
			(size 0.519938 1.4986)
			(layers "F.Cu" "F.Mask" "F.Paste")
			(net "GND")
		)
		(pad "72" smd rect
			(at -2.050034 -2.975102 90)
			(size 0.519938 1.4986)
			(layers "F.Cu" "F.Mask" "F.Paste")
			(net "M_J_CPU1_SA_CA<6>")
		)
		(pad "73" smd rect
			(at -2.050034 -2.124964 90)
			(size 0.519938 1.4986)
			(layers "F.Cu" "F.Mask" "F.Paste")
			(net "GND")
		)
		(pad "74" smd rect
			(at -2.050034 -1.27508 90)
			(size 0.519938 1.4986)
			(layers "F.Cu" "F.Mask" "F.Paste")
			(net "M_J_CPU1_SA_PAR")
		)
		(pad "75" smd rect
			(at -2.050034 -0.424942 90)
			(size 0.519938 1.4986)
			(layers "F.Cu" "F.Mask" "F.Paste")
			(net "GND")
		)
		(pad "76" smd rect
			(at -2.050034 5.525008 90)
			(size 0.519938 1.4986)
			(layers "F.Cu" "F.Mask" "F.Paste")
			(net "M_J_CPU1_SB_CA<0>")
		)
		(pad "77" smd rect
			(at -2.050034 6.374892 90)
			(size 0.519938 1.4986)
			(layers "F.Cu" "F.Mask" "F.Paste")
			(net "GND")
		)
		(pad "78" smd rect
			(at -2.050034 7.22503 90)
			(size 0.519938 1.4986)
			(layers "F.Cu" "F.Mask" "F.Paste")
			(net "M_J_CPU1_SB_CA<2>")
		)
		(pad "79" smd rect
			(at -2.050034 8.074914 90)
			(size 0.519938 1.4986)
			(layers "F.Cu" "F.Mask" "F.Paste")
			(net "GND")
		)
		(pad "80" smd rect
			(at -2.050034 8.925052 90)
			(size 0.519938 1.4986)
			(layers "F.Cu" "F.Mask" "F.Paste")
			(net "M_J_CPU1_SB_CA<4>")
		)
		(pad "81" smd rect
			(at -2.050034 9.774936 90)
			(size 0.519938 1.4986)
			(layers "F.Cu" "F.Mask" "F.Paste")
			(net "GND")
		)
		(pad "82" smd rect
			(at -2.050034 10.625074 90)
			(size 0.519938 1.4986)
			(layers "F.Cu" "F.Mask" "F.Paste")
			(net "M_J_CPU1_SB_CA<6>")
		)
		(pad "83" smd rect
			(at -2.050034 11.474958 90)
			(size 0.519938 1.4986)
			(layers "F.Cu" "F.Mask" "F.Paste")
			(net "GND")
		)
		(pad "84" smd rect
			(at -2.050034 12.325096 90)
			(size 0.519938 1.4986)
			(layers "F.Cu" "F.Mask" "F.Paste")
			(net "M_J_CPU1_SB_CS_N<0>")
		)
		(pad "85" smd rect
			(at -2.050034 13.17498 90)
			(size 0.519938 1.4986)
			(layers "F.Cu" "F.Mask" "F.Paste")
			(net "GND")
		)
		(pad "86" smd rect
			(at -2.050034 14.025118 90)
			(size 0.519938 1.4986)
			(layers "F.Cu" "F.Mask" "F.Paste")
			(net "M_J_CPU1_SA_RSP<0>")
		)
		(pad "87" smd rect
			(at -2.050034 14.875002 90)
			(size 0.519938 1.4986)
			(layers "F.Cu" "F.Mask" "F.Paste")
			(net "M_J_CPU1_SB_RSP<0>")
		)
		(pad "88" smd rect
			(at -2.050034 15.724886 90)
			(size 0.519938 1.4986)
			(layers "F.Cu" "F.Mask" "F.Paste")
			(net "GND")
		)
		(pad "89" smd rect
			(at -2.050034 16.575024 90)
			(size 0.519938 1.4986)
			(layers "F.Cu" "F.Mask" "F.Paste")
			(net "M_J_CPU1_SB_CB<4>")
		)
		(pad "90" smd rect
			(at -2.050034 17.424908 90)
			(size 0.519938 1.4986)
			(layers "F.Cu" "F.Mask" "F.Paste")
			(net "GND")
		)
		(pad "91" smd rect
			(at -2.050034 18.275046 90)
			(size 0.519938 1.4986)
			(layers "F.Cu" "F.Mask" "F.Paste")
			(net "M_J_CPU1_SB_CB<5>")
		)
	)
)
